# S9S_MB_2U (Grand Teton) — schematic netlist excerpt (pin names and nets, part order shuffled) for the footprints in the layout excerpt that follows; sources: Cadence DE-HDL packaged netlist, KiCad conversion of 03242023_DA0F0TMBIJ0_F0T_Motherboard_J_brd_V01_OCP.brd

C54  Q_CAP  10UF 16V 10% X6S  pkg C0805  page 99 : A = P12V_S3_AUX_CPU1_NVDIMM ; B = GND
R3213  Q_RES  0 5% EMPTY  pkg 0402LF  page 160 : A = NCSI_BMC_TX_EN_R1 ; B = RMII_BMC_OCP_TX_EN
R75  Q_RES  54.9K 1% CHIP  pkg 0402LF  page 110 : A = PD_CHG_CPU1_DIMM1_SAA ; B = GND

(kicad_pcb
	(version 20260206)
	(generator "pcbnew")
	(generator_version "10.0")
	(general
		(thickness 1.6)
		(legacy_teardrops no)
	)
	(paper "A4")
	(title_block
		(title "03242023_DA0F0TMBIJ0_F0T_Motherboard_J_brd_V01_OCP.brd")
		(comment 1 "Grand Teton / footprints 5806-5808 of 6105")
	)
	(layers
		(0 "F.Cu" signal "TOP")
		(4 "In1.Cu" signal "GND")
		(6 "In2.Cu" signal "IN1")
		(8 "In3.Cu" signal "GND1")
		(10 "In4.Cu" signal "IN2")
		(12 "In5.Cu" signal "GND2")
		(14 "In6.Cu" signal "IN3")
		(16 "In7.Cu" signal "GND3")
		(18 "In8.Cu" signal "VCC")
		(20 "In9.Cu" signal "VCC1")
		(22 "In10.Cu" signal "GND4")
		(24 "In11.Cu" signal "IN4")
		(26 "In12.Cu" signal "GND5")
		(28 "In13.Cu" signal "IN5")
		(30 "In14.Cu" signal "GND6")
		(32 "In15.Cu" signal "IN6")
		(34 "In16.Cu" signal "GND7")
		(2 "B.Cu" signal "BOTTOM")
		(9 "F.Adhes" user "F.Adhesive")
		(11 "B.Adhes" user "B.Adhesive")
		(13 "F.Paste" user "Package Geometry/Pastemask Top")
		(15 "B.Paste" user "Package Geometry/Pastemask Bottom")
		(5 "F.SilkS" user "Ref Des/Silkscreen Top")
		(7 "B.SilkS" user "Ref Des/Silkscreen Bottom")
		(1 "F.Mask" user "Board Geometry/Soldermask Top")
		(3 "B.Mask" user "Board Geometry/Soldermask Bottom")
		(17 "Dwgs.User" user "User.Drawings")
		(19 "Cmts.User" user "User.Comments")
		(21 "Eco1.User" user "User.Eco1")
		(23 "Eco2.User" user "User.Eco2")
		(25 "Edge.Cuts" user "Board Geometry/Outline")
		(27 "Margin" user)
		(31 "F.CrtYd" user "Package Geometry/Place Bound Top")
		(29 "B.CrtYd" user "Package Geometry/Place Bound Bottom")
		(35 "F.Fab" user "Ref Des/Assembly Top")
		(33 "B.Fab" user "Ref Des/Assembly Bottom")
	)
	(footprint ""
		(layer "B.Cu")
		(at 198.086472 -318.332358)
		(property "Reference" "R75"
			(at 0 0 0)
			(layer "B.SilkS")
			(hide yes)
			(effects
				(font
					(size 1.27 1.27)
				)
				(justify mirror)
			)
		)
		(property "Value" ""
			(at 0 0 0)
			(layer "B.Fab")
			(effects
				(font
					(size 1.27 1.27)
				)
				(justify mirror)
			)
		)
		(duplicate_pad_numbers_are_jumpers no)
		(fp_line
			(start -0.7874 -0.4064)
			(end -0.7874 0.4064)
			(stroke
				(width 0.1524)
				(type default)
			)
			(layer "B.SilkS")
		)
		(fp_line
			(start -0.7874 0.4064)
			(end 0.7874 0.4064)
			(stroke
				(width 0.1524)
				(type default)
			)
			(layer "B.SilkS")
		)
		(fp_line
			(start 0.7874 -0.4064)
			(end -0.7874 -0.4064)
			(stroke
				(width 0.1524)
				(type default)
			)
			(layer "B.SilkS")
		)
		(fp_line
			(start 0.7874 0.4064)
			(end 0.7874 -0.4064)
			(stroke
				(width 0.1524)
				(type default)
			)
			(layer "B.SilkS")
		)
		(fp_line
			(start -0.67945 -0.3048)
			(end -0.67945 0.3048)
			(stroke
				(width 0.1)
				(type default)
			)
			(layer "B.Fab")
		)
		(fp_line
			(start -0.67945 0.3048)
			(end -0.120396 0.3048)
			(stroke
				(width 0.1)
				(type default)
			)
			(layer "B.Fab")
		)
		(fp_line
			(start -0.12065 -0.3048)
			(end -0.67945 -0.3048)
			(stroke
				(width 0.1)
				(type default)
			)
			(layer "B.Fab")
		)
		(fp_line
			(start -0.12065 -0.2794)
			(end -0.12065 -0.3048)
			(stroke
				(width 0.1)
				(type default)
			)
			(layer "B.Fab")
		)
		(fp_line
			(start -0.120396 0.2794)
			(end 0.12065 0.2794)
			(stroke
				(width 0.1)
				(type default)
			)
			(layer "B.Fab")
		)
		(fp_line
			(start -0.120396 0.3048)
			(end -0.120396 0.2794)
			(stroke
				(width 0.1)
				(type default)
			)
			(layer "B.Fab")
		)
		(fp_line
			(start 0.12065 -0.305054)
			(end 0.12065 -0.2794)
			(stroke
				(width 0.1)
				(type default)
			)
			(layer "B.Fab")
		)
		(fp_line
			(start 0.12065 -0.2794)
			(end -0.12065 -0.2794)
			(stroke
				(width 0.1)
				(type default)
			)
			(layer "B.Fab")
		)
		(fp_line
			(start 0.12065 0.2794)
			(end 0.12065 0.3048)
			(stroke
				(width 0.1)
				(type default)
			)
			(layer "B.Fab")
		)
		(fp_line
			(start 0.12065 0.3048)
			(end 0.67945 0.3048)
			(stroke
				(width 0.1)
				(type default)
			)
			(layer "B.Fab")
		)
		(fp_line
			(start 0.67945 -0.305054)
			(end 0.12065 -0.305054)
			(stroke
				(width 0.1)
				(type default)
			)
			(layer "B.Fab")
		)
		(fp_line
			(start 0.67945 0.3048)
			(end 0.67945 -0.305054)
			(stroke
				(width 0.1)
				(type default)
			)
			(layer "B.Fab")
		)
		(pad "1" smd circle
			(at 0.40005 0 180)
			(size 0 0)
			(layers "B.Cu" "B.Mask" "B.Paste")
			(net "PD_CHG_CPU1_DIMM1_SAA")
		)
		(pad "2" smd circle
			(at -0.40005 0 180)
			(size 0 0)
			(layers "B.Cu" "B.Mask" "B.Paste")
			(net "GND")
		)
	)
	(footprint ""
		(layer "B.Cu")
		(at 65.023746 -321.554856 -90)
		(property "Reference" "C54"
			(at 0 0 90)
			(layer "B.SilkS")
			(hide yes)
			(effects
				(font
					(size 1.27 1.27)
				)
				(justify mirror)
			)
		)
		(property "Value" ""
			(at 0 0 90)
			(layer "B.Fab")
			(effects
				(font
					(size 1.27 1.27)
				)
				(justify mirror)
			)
		)
		(duplicate_pad_numbers_are_jumpers no)
		(fp_line
			(start -1.524 0.762)
			(end 1.524 0.762)
			(stroke
				(width 0.1524)
				(type default)
			)
			(layer "B.SilkS")
		)
		(fp_line
			(start 1.524 0.762)
			(end 1.524 -0.762)
			(stroke
				(width 0.1524)
				(type default)
			)
			(layer "B.SilkS")
		)
		(fp_line
			(start -1.524 -0.762)
			(end -1.524 0.762)
			(stroke
				(width 0.1524)
				(type default)
			)
			(layer "B.SilkS")
		)
		(fp_line
			(start 1.524 -0.762)
			(end -1.524 -0.762)
			(stroke
				(width 0.1524)
				(type default)
			)
			(layer "B.SilkS")
		)
		(fp_line
			(start -1.1049 0.724916)
			(end -1.1049 -0.724916)
			(stroke
				(width 0.1)
				(type default)
			)
			(layer "B.Fab")
		)
		(fp_line
			(start 1.1049 0.724916)
			(end -1.1049 0.724916)
			(stroke
				(width 0.1)
				(type default)
			)
			(layer "B.Fab")
		)
		(fp_line
			(start -1.1049 -0.724916)
			(end 1.1049 -0.724916)
			(stroke
				(width 0.1)
				(type default)
			)
			(layer "B.Fab")
		)
		(fp_line
			(start 1.1049 -0.724916)
			(end 1.1049 0.724916)
			(stroke
				(width 0.1)
				(type default)
			)
			(layer "B.Fab")
		)
		(pad "1" smd rect
			(at 0.889 0 270)
			(size 1.016 1.27)
			(layers "B.Cu" "B.Mask" "B.Paste")
			(net "P12V_S3_AUX_CPU1_NVDIMM")
		)
		(pad "2" smd rect
			(at -0.889 0 270)
			(size 1.016 1.27)
			(layers "B.Cu" "B.Mask" "B.Paste")
			(net "GND")
		)
	)
	(footprint ""
		(layer "B.Cu")
		(at 191.992758 -69.443346)
		(property "Reference" "R3213"
			(at 0 0 0)
			(layer "B.SilkS")
			(hide yes)
			(effects
				(font
					(size 1.27 1.27)
				)
				(justify mirror)
			)
		)
		(property "Value" ""
			(at 0 0 0)
			(layer "B.Fab")
			(effects
				(font
					(size 1.27 1.27)
				)
				(justify mirror)
			)
		)
		(duplicate_pad_numbers_are_jumpers no)
		(fp_line
			(start -0.7874 -0.4064)
			(end -0.7874 0.4064)
			(stroke
				(width 0.1524)
				(type default)
			)
			(layer "B.SilkS")
		)
		(fp_line
			(start -0.7874 0.4064)
			(end 0.7874 0.4064)
			(stroke
				(width 0.1524)
				(type default)
			)
			(layer "B.SilkS")
		)
		(fp_line
			(start 0.7874 -0.4064)
			(end -0.7874 -0.4064)
			(stroke
				(width 0.1524)
				(type default)
			)
			(layer "B.SilkS")
		)
		(fp_line
			(start 0.7874 0.4064)
			(end 0.7874 -0.4064)
			(stroke
				(width 0.1524)
				(type default)
			)
			(layer "B.SilkS")
		)
		(fp_line
			(start -0.67945 -0.3048)
			(end -0.67945 0.3048)
			(stroke
				(width 0.1)
				(type default)
			)
			(layer "B.Fab")
		)
		(fp_line
			(start -0.67945 0.3048)
			(end -0.120396 0.3048)
			(stroke
				(width 0.1)
				(type default)
			)
			(layer "B.Fab")
		)
		(fp_line
			(start -0.12065 -0.3048)
			(end -0.67945 -0.3048)
			(stroke
				(width 0.1)
				(type default)
			)
			(layer "B.Fab")
		)
		(fp_line
			(start -0.12065 -0.2794)
			(end -0.12065 -0.3048)
			(stroke
				(width 0.1)
				(type default)
			)
			(layer "B.Fab")
		)
		(fp_line
			(start -0.120396 0.2794)
			(end 0.12065 0.2794)
			(stroke
				(width 0.1)
				(type default)
			)
			(layer "B.Fab")
		)
		(fp_line
			(start -0.120396 0.3048)
			(end -0.120396 0.2794)
			(stroke
				(width 0.1)
				(type default)
			)
			(layer "B.Fab")
		)
		(fp_line
			(start 0.12065 -0.305054)
			(end 0.12065 -0.2794)
			(stroke
				(width 0.1)
				(type default)
			)
			(layer "B.Fab")
		)
		(fp_line
			(start 0.12065 -0.2794)
			(end -0.12065 -0.2794)
			(stroke
				(width 0.1)
				(type default)
			)
			(layer "B.Fab")
		)
		(fp_line
			(start 0.12065 0.2794)
			(end 0.12065 0.3048)
			(stroke
				(width 0.1)
				(type default)
			)
			(layer "B.Fab")
		)
		(fp_line
			(start 0.12065 0.3048)
			(end 0.67945 0.3048)
			(stroke
				(width 0.1)
				(type default)
			)
			(layer "B.Fab")
		)
		(fp_line
			(start 0.67945 -0.305054)
			(end 0.12065 -0.305054)
			(stroke
				(width 0.1)
				(type default)
			)
			(layer "B.Fab")
		)
		(fp_line
			(start 0.67945 0.3048)
			(end 0.67945 -0.305054)
			(stroke
				(width 0.1)
				(type default)
			)
			(layer "B.Fab")
		)
		(pad "1" smd circle
			(at 0.40005 0 180)
			(size 0 0)
			(layers "B.Cu" "B.Mask" "B.Paste")
			(net "NCSI_BMC_TX_EN_R1")
		)
		(pad "2" smd circle
			(at -0.40005 0 180)
			(size 0 0)
			(layers "B.Cu" "B.Mask" "B.Paste")
			(net "RMII_BMC_OCP_TX_EN")
		)
	)
)
